#ISCELL
  mstr_misc dns *
  *
#ISCELL
  pure_quanta quanta_title_block_c *
  *
#ISCELL
  pure_quanta_power design_note *
  *
#ISCELL
  standard offpage *
  page232_i1
#ISCELL
  pure_quanta_power universal_gnd *
  page232_i11
#ISCELL
  pure_quanta_power universal_gnd *
  page232_i12
#CELL
  pure_quanta q_xtal_4p_13bi_24gnd *
  page232_i14
#ISCELL
  pure_quanta_power universal_power *
  page232_i15
#CELL
  pure_quanta q_res *
  page232_i16
#ISCELL
  standard offpage *
  page232_i17
#ISCELL
  standard offpage *
  page232_i18
#ISCELL
  pure_quanta_power universal_gnd *
  page232_i19
#ISCELL
  standard offpage *
  page232_i2
#ISCELL
  pure_quanta_power universal_gnd *
  page232_i20
#CELL
  pure_quanta q_res *
  page232_i22
#ISCELL
  standard offpage *
  page232_i23
#ISCELL
  standard offpage *
  page232_i24
#ISCELL
  pure_quanta_power universal_gnd *
  page232_i25
#CELL
  pure_quanta 74lvc1g32gw *
  page232_i26
#ISCELL
  pure_quanta_power universal_gnd *
  page232_i27
#CELL
  pure_quanta q_cap *
  page232_i28
#ISCELL
  pure_quanta_power universal_power *
  page232_i29
#ISCELL
  standard offpage *
  page232_i3
#ISCELL
  pure_quanta_power universal_power *
  page232_i30
#CELL
  pure_quanta q_res *
  page232_i31
#ISCELL
  pure_quanta_power universal_power *
  page232_i32
#CELL
  pure_quanta q_inductor *
  page232_i33
#ISCELL
  pure_quanta_power universal_power *
  page232_i34
#ISCELL
  pure_quanta_power universal_power *
  page232_i35
#CELL
  pure_quanta q_cap *
  page232_i36
#CELL
  pure_quanta q_cap *
  page232_i37
#ISCELL
  pure_quanta_power universal_power *
  page232_i38
#ISCELL
  pure_quanta_power universal_gnd *
  page232_i39
#ISCELL
  standard offpage *
  page232_i4
#CELL
  pure_quanta q_cap *
  page232_i40
#CELL
  pure_quanta q_cap *
  page232_i41
#CELL
  pure_quanta q_cap *
  page232_i42
#CELL
  pure_quanta q_res *
  page232_i43
#ISCELL
  standard offpage *
  page232_i44
#ISCELL
  pure_quanta_power universal_gnd *
  page232_i45
#CELL
  pure_quanta q_res *
  page232_i46
#CELL
  pure_quanta q_res *
  page232_i47
#ISCELL
  pure_quanta_power universal_power *
  page232_i48
#ISCELL
  standard offpage *
  page232_i49
#ISCELL
  pure_quanta_power universal_gnd *
  page232_i5
#CELL
  pure_quanta q_res *
  page232_i50
#CELL
  pure_quanta q_res *
  page232_i51
#CELL
  pure_quanta q_res *
  page232_i52
#CELL
  pure_quanta q_res *
  page232_i53
#ISCELL
  pure_quanta_power universal_gnd *
  page232_i54
#CELL
  pure_quanta q_res *
  page232_i55
#CELL
  pure_quanta q_res *
  page232_i56
#ISCELL
  pure_quanta_power universal_power *
  page232_i57
#ISCELL
  standard offpage *
  page232_i58
#CELL
  pure_quanta q_res *
  page232_i59
#CELL
  pure_quanta q_res *
  page232_i6
#ISCELL
  pure_quanta_power universal_power *
  page232_i60
#ISCELL
  standard offpage *
  page232_i61
#ISCELL
  standard offpage *
  page232_i62
#ISCELL
  standard offpage *
  page232_i63
#ISCELL
  standard offpage *
  page232_i64
#ISCELL
  standard offpage *
  page232_i65
#ISCELL
  pure_quanta_power universal_gnd *
  page232_i66
#ISCELL
  standard offpage *
  page232_i67
#CELL
  pure_quanta q_cap *
  page232_i68
#CELL
  pure_quanta q_cap *
  page232_i69
#CELL
  pure_quanta q_res *
  page232_i7
#ISCELL
  pure_quanta_power universal_power *
  page232_i70
#ISCELL
  pure_quanta_power universal_gnd *
  page232_i71
#CELL
  pure_quanta q_res *
  page232_i73
#CELL
  pure_quanta q_res *
  page232_i74
#CELL
  pure_quanta q_cap *
  page232_i75
#CELL
  pure_quanta q_cap *
  page232_i76
#CELL
  pure_quanta 9fgl0251dkilft *
  page232_i77
#CELL
  pure_quanta q_res *
  page232_i8
